FILE_TYPE = MACRO_DRAWING;
SET COLOR_WIRE YELLOW;
SET COLOR_PROP ORANGE;
SET COLOR_DOT WHITE;
SET COLOR_ARC YELLOW;
SET COLOR_BODY GREEN;
SET COLOR_NOTE PURPLE;
SET PROP_DISPLAY VALUE;
SET PAGE_NUMBER P66;
FORCEADD SOCKET4677_AZIF0045P001C01CS..25
(600 2750);
FORCEPROP 1 LAST PART_NUMBER DGA^7000023
J 0
(-450 4200);
DISPLAY 0.723404 (-450 4200);
PAINT GREEN (-450 4200);
DISPLAY INVISIBLE (-450 4200);
FORCEPROP 2 LAST PART_TYPE SMLF
J 0
(-450 4375);
DISPLAY 1.021277 (-450 4375);
FORCEPROP 1 LAST MATERIAL IO
J 0
(-450 4125);
DISPLAY 0.723404 (-450 4125);
PAINT GREEN (-450 4125);
FORCEPROP 2 LAST VALUE SOCKET4677_AZIF0045-P001C01CS
J 0
(-450 4325);
DISPLAY 1.021277 (-450 4325);
FORCEPROP 1 LAST $LOCATION U1
J 0
(-450 4275);
DISPLAY 0.723404 (-450 4275);
PAINT GREEN (-450 4275);
FORCEPROP 0 LASTPIN (-600 1550) $PN EJ80
J 2
(-610 1560);
DISPLAY 0.680851 (-610 1560);
PAINT MONO (-610 1560);
FORCEPROP 0 LASTPIN (-600 1600) $PN EP81
J 2
(-610 1610);
DISPLAY 0.680851 (-610 1610);
PAINT MONO (-610 1610);
FORCEPROP 0 LASTPIN (-600 1650) $PN EL82
J 2
(-610 1660);
DISPLAY 0.680851 (-610 1660);
PAINT MONO (-610 1660);
FORCEPROP 0 LASTPIN (-600 1700) $PN EK81
J 2
(-610 1710);
DISPLAY 0.680851 (-610 1710);
PAINT MONO (-610 1710);
FORCEPROP 0 LASTPIN (-600 1750) $PN EF81
J 2
(-610 1760);
DISPLAY 0.680851 (-610 1760);
PAINT MONO (-610 1760);
FORCEPROP 0 LASTPIN (-600 1800) $PN ED83
J 2
(-610 1810);
DISPLAY 0.680851 (-610 1810);
PAINT MONO (-610 1810);
FORCEPROP 0 LASTPIN (-600 1850) $PN EC80
J 2
(-610 1860);
DISPLAY 0.680851 (-610 1860);
PAINT MONO (-610 1860);
FORCEPROP 0 LASTPIN (-600 1900) $PN EA82
J 2
(-610 1910);
DISPLAY 0.680851 (-610 1910);
PAINT MONO (-610 1910);
FORCEPROP 0 LASTPIN (-600 1950) $PN DY81
J 2
(-610 1960);
DISPLAY 0.680851 (-610 1960);
PAINT MONO (-610 1960);
FORCEPROP 0 LASTPIN (-600 2000) $PN DJ78
J 2
(-610 2010);
DISPLAY 0.680851 (-610 2010);
PAINT MONO (-610 2010);
FORCEPROP 0 LASTPIN (-600 2050) $PN DG78
J 2
(-610 2060);
DISPLAY 0.680851 (-610 2060);
PAINT MONO (-610 2060);
FORCEPROP 0 LASTPIN (-600 2100) $PN DH81
J 2
(-610 2110);
DISPLAY 0.680851 (-610 2110);
PAINT MONO (-610 2110);
FORCEPROP 0 LASTPIN (-600 2150) $PN DF83
J 2
(-610 2160);
DISPLAY 0.680851 (-610 2160);
PAINT MONO (-610 2160);
FORCEPROP 0 LASTPIN (-600 2200) $PN DE80
J 2
(-610 2210);
DISPLAY 0.680851 (-610 2210);
PAINT MONO (-610 2210);
FORCEPROP 0 LASTPIN (-600 2250) $PN DC82
J 2
(-610 2260);
DISPLAY 0.680851 (-610 2260);
PAINT MONO (-610 2260);
FORCEPROP 0 LASTPIN (-600 2300) $PN DB81
J 2
(-610 2310);
DISPLAY 0.680851 (-610 2310);
PAINT MONO (-610 2310);
FORCEPROP 0 LASTPIN (-600 2350) $PN DF77
J 2
(-610 2360);
DISPLAY 0.680851 (-610 2360);
PAINT MONO (-610 2360);
FORCEPROP 0 LASTPIN (-600 2400) $PN CU82
J 2
(-610 2410);
DISPLAY 0.680851 (-610 2410);
PAINT MONO (-610 2410);
FORCEPROP 0 LASTPIN (-600 2450) $PN CR82
J 2
(-610 2460);
DISPLAY 0.680851 (-610 2460);
PAINT MONO (-610 2460);
FORCEPROP 0 LASTPIN (-600 2500) $PN CW80
J 2
(-610 2510);
DISPLAY 0.680851 (-610 2510);
PAINT MONO (-610 2510);
FORCEPROP 0 LASTPIN (-600 2550) $PN CP81
J 2
(-610 2560);
DISPLAY 0.680851 (-610 2560);
PAINT MONO (-610 2560);
FORCEPROP 0 LASTPIN (-600 2600) $PN CN80
J 2
(-610 2610);
DISPLAY 0.680851 (-610 2610);
PAINT MONO (-610 2610);
FORCEPROP 0 LASTPIN (-600 2650) $PN CT79
J 2
(-610 2660);
DISPLAY 0.680851 (-610 2660);
PAINT MONO (-610 2660);
FORCEPROP 0 LASTPIN (-600 2700) $PN DA78
J 2
(-610 2710);
DISPLAY 0.680851 (-610 2710);
PAINT MONO (-610 2710);
FORCEPROP 0 LASTPIN (-600 2800) $PN EL80
J 2
(-610 2810);
DISPLAY 0.680851 (-610 2810);
PAINT MONO (-610 2810);
FORCEPROP 0 LASTPIN (-600 2850) $PN ER82
J 2
(-610 2860);
DISPLAY 0.680851 (-610 2860);
PAINT MONO (-610 2860);
FORCEPROP 0 LASTPIN (-600 2900) $PN EN82
J 2
(-610 2910);
DISPLAY 0.680851 (-610 2910);
PAINT MONO (-610 2910);
FORCEPROP 0 LASTPIN (-600 2950) $PN EJ82
J 2
(-610 2960);
DISPLAY 0.680851 (-610 2960);
PAINT MONO (-610 2960);
FORCEPROP 0 LASTPIN (-600 3000) $PN EE82
J 2
(-610 3010);
DISPLAY 0.680851 (-610 3010);
PAINT MONO (-610 3010);
FORCEPROP 0 LASTPIN (-600 3050) $PN EF83
J 2
(-610 3060);
DISPLAY 0.680851 (-610 3060);
PAINT MONO (-610 3060);
FORCEPROP 0 LASTPIN (-600 3100) $PN ED81
J 2
(-610 3110);
DISPLAY 0.680851 (-610 3110);
PAINT MONO (-610 3110);
FORCEPROP 0 LASTPIN (-600 3150) $PN DY83
J 2
(-610 3160);
DISPLAY 0.680851 (-610 3160);
PAINT MONO (-610 3160);
FORCEPROP 0 LASTPIN (-600 3200) $PN EB81
J 2
(-610 3210);
DISPLAY 0.680851 (-610 3210);
PAINT MONO (-610 3210);
FORCEPROP 0 LASTPIN (-600 3250) $PN DL78
J 2
(-610 3260);
DISPLAY 0.680851 (-610 3260);
PAINT MONO (-610 3260);
FORCEPROP 0 LASTPIN (-600 3300) $PN DH79
J 2
(-610 3310);
DISPLAY 0.680851 (-610 3310);
PAINT MONO (-610 3310);
FORCEPROP 0 LASTPIN (-600 3350) $PN DG82
J 2
(-610 3360);
DISPLAY 0.680851 (-610 3360);
PAINT MONO (-610 3360);
FORCEPROP 0 LASTPIN (-600 3400) $PN DH83
J 2
(-610 3410);
DISPLAY 0.680851 (-610 3410);
PAINT MONO (-610 3410);
FORCEPROP 0 LASTPIN (-600 3450) $PN DF81
J 2
(-610 3460);
DISPLAY 0.680851 (-610 3460);
PAINT MONO (-610 3460);
FORCEPROP 0 LASTPIN (-600 3500) $PN DB83
J 2
(-610 3510);
DISPLAY 0.680851 (-610 3510);
PAINT MONO (-610 3510);
FORCEPROP 0 LASTPIN (-600 3550) $PN DD81
J 2
(-610 3560);
DISPLAY 0.680851 (-610 3560);
PAINT MONO (-610 3560);
FORCEPROP 0 LASTPIN (-600 3600) $PN DE78
J 2
(-610 3610);
DISPLAY 0.680851 (-610 3610);
PAINT MONO (-610 3610);
FORCEPROP 0 LASTPIN (-600 3650) $PN CW82
J 2
(-610 3660);
DISPLAY 0.680851 (-610 3660);
PAINT MONO (-610 3660);
FORCEPROP 0 LASTPIN (-600 3700) $PN CT83
J 2
(-610 3710);
DISPLAY 0.680851 (-610 3710);
PAINT MONO (-610 3710);
FORCEPROP 0 LASTPIN (-600 3750) $PN CV81
J 2
(-610 3760);
DISPLAY 0.680851 (-610 3760);
PAINT MONO (-610 3760);
FORCEPROP 0 LASTPIN (-600 3800) $PN CN82
J 2
(-610 3810);
DISPLAY 0.680851 (-610 3810);
PAINT MONO (-610 3810);
FORCEPROP 0 LASTPIN (-600 3850) $PN CR80
J 2
(-610 3860);
DISPLAY 0.680851 (-610 3860);
PAINT MONO (-610 3860);
FORCEPROP 0 LASTPIN (-600 3900) $PN CU80
J 2
(-610 3910);
DISPLAY 0.680851 (-610 3910);
PAINT MONO (-610 3910);
FORCEPROP 0 LASTPIN (-600 3950) $PN DB79
J 2
(-610 3960);
DISPLAY 0.680851 (-610 3960);
PAINT MONO (-610 3960);
FORCEPROP 0 LASTPIN (1800 1550) $PN EH85
J 0
(1810 1560);
DISPLAY 0.680851 (1810 1560);
PAINT MONO (1810 1560);
FORCEPROP 0 LASTPIN (1800 1600) $PN EL84
J 0
(1810 1610);
DISPLAY 0.680851 (1810 1610);
PAINT MONO (1810 1610);
FORCEPROP 0 LASTPIN (1800 1650) $PN EP85
J 0
(1810 1660);
DISPLAY 0.680851 (1810 1660);
PAINT MONO (1810 1660);
FORCEPROP 0 LASTPIN (1800 1700) $PN EM87
J 0
(1810 1710);
DISPLAY 0.680851 (1810 1710);
PAINT MONO (1810 1710);
FORCEPROP 0 LASTPIN (1800 1750) $PN EJ86
J 0
(1810 1760);
DISPLAY 0.680851 (1810 1760);
PAINT MONO (1810 1760);
FORCEPROP 0 LASTPIN (1800 1800) $PN EK87
J 0
(1810 1810);
DISPLAY 0.680851 (1810 1810);
PAINT MONO (1810 1810);
FORCEPROP 0 LASTPIN (1800 1850) $PN DU80
J 0
(1810 1860);
DISPLAY 0.680851 (1810 1860);
PAINT MONO (1810 1860);
FORCEPROP 0 LASTPIN (1800 1900) $PN DR82
J 0
(1810 1910);
DISPLAY 0.680851 (1810 1910);
PAINT MONO (1810 1910);
FORCEPROP 0 LASTPIN (1800 1950) $PN DP79
J 0
(1810 1960);
DISPLAY 0.680851 (1810 1960);
PAINT MONO (1810 1960);
FORCEPROP 0 LASTPIN (1800 2000) $PN DN82
J 0
(1810 2010);
DISPLAY 0.680851 (1810 2010);
PAINT MONO (1810 2010);
FORCEPROP 0 LASTPIN (1800 2050) $PN DM81
J 0
(1810 2060);
DISPLAY 0.680851 (1810 2060);
PAINT MONO (1810 2060);
FORCEPROP 0 LASTPIN (1800 2100) $PN DL80
J 0
(1810 2110);
DISPLAY 0.680851 (1810 2110);
PAINT MONO (1810 2110);
FORCEPROP 0 LASTPIN (1800 2150) $PN CW76
J 0
(1810 2160);
DISPLAY 0.680851 (1810 2160);
PAINT MONO (1810 2160);
FORCEPROP 0 LASTPIN (1800 2200) $PN CU76
J 0
(1810 2210);
DISPLAY 0.680851 (1810 2210);
PAINT MONO (1810 2210);
FORCEPROP 0 LASTPIN (1800 2250) $PN CT75
J 0
(1810 2260);
DISPLAY 0.680851 (1810 2260);
PAINT MONO (1810 2260);
FORCEPROP 0 LASTPIN (1800 2300) $PN CR74
J 0
(1810 2310);
DISPLAY 0.680851 (1810 2310);
PAINT MONO (1810 2310);
FORCEPROP 0 LASTPIN (1800 2350) $PN CK77
J 0
(1810 2360);
DISPLAY 0.680851 (1810 2360);
PAINT MONO (1810 2360);
FORCEPROP 0 LASTPIN (1800 2400) $PN CH77
J 0
(1810 2410);
DISPLAY 0.680851 (1810 2410);
PAINT MONO (1810 2410);
FORCEPROP 0 LASTPIN (1800 2450) $PN CM75
J 0
(1810 2460);
DISPLAY 0.680851 (1810 2460);
PAINT MONO (1810 2460);
FORCEPROP 0 LASTPIN (1800 2500) $PN CG76
J 0
(1810 2510);
DISPLAY 0.680851 (1810 2510);
PAINT MONO (1810 2510);
FORCEPROP 0 LASTPIN (1800 2550) $PN CF75
J 0
(1810 2560);
DISPLAY 0.680851 (1810 2560);
PAINT MONO (1810 2560);
FORCEPROP 0 LASTPIN (1800 2600) $PN CJ74
J 0
(1810 2610);
DISPLAY 0.680851 (1810 2610);
PAINT MONO (1810 2610);
FORCEPROP 0 LASTPIN (1800 2650) $PN CV73
J 0
(1810 2660);
DISPLAY 0.680851 (1810 2660);
PAINT MONO (1810 2660);
FORCEPROP 0 LASTPIN (1800 2700) $PN CF73
J 0
(1810 2710);
DISPLAY 0.680851 (1810 2710);
PAINT MONO (1810 2710);
FORCEPROP 0 LASTPIN (1800 2800) $PN EK85
J 0
(1810 2810);
DISPLAY 0.680851 (1810 2810);
PAINT MONO (1810 2810);
FORCEPROP 0 LASTPIN (1800 2850) $PN EM85
J 0
(1810 2860);
DISPLAY 0.680851 (1810 2860);
PAINT MONO (1810 2860);
FORCEPROP 0 LASTPIN (1800 2900) $PN EN86
J 0
(1810 2910);
DISPLAY 0.680851 (1810 2910);
PAINT MONO (1810 2910);
FORCEPROP 0 LASTPIN (1800 2950) $PN EP87
J 0
(1810 2960);
DISPLAY 0.680851 (1810 2960);
PAINT MONO (1810 2960);
FORCEPROP 0 LASTPIN (1800 3000) $PN EH87
J 0
(1810 3010);
DISPLAY 0.680851 (1810 3010);
PAINT MONO (1810 3010);
FORCEPROP 0 LASTPIN (1800 3050) $PN EL88
J 0
(1810 3060);
DISPLAY 0.680851 (1810 3060);
PAINT MONO (1810 3060);
FORCEPROP 0 LASTPIN (1800 3100) $PN DT81
J 0
(1810 3110);
DISPLAY 0.680851 (1810 3110);
PAINT MONO (1810 3110);
FORCEPROP 0 LASTPIN (1800 3150) $PN DU82
J 0
(1810 3160);
DISPLAY 0.680851 (1810 3160);
PAINT MONO (1810 3160);
FORCEPROP 0 LASTPIN (1800 3200) $PN DR80
J 0
(1810 3210);
DISPLAY 0.680851 (1810 3210);
PAINT MONO (1810 3210);
FORCEPROP 0 LASTPIN (1800 3250) $PN DP83
J 0
(1810 3260);
DISPLAY 0.680851 (1810 3260);
PAINT MONO (1810 3260);
FORCEPROP 0 LASTPIN (1800 3300) $PN DL82
J 0
(1810 3310);
DISPLAY 0.680851 (1810 3310);
PAINT MONO (1810 3310);
FORCEPROP 0 LASTPIN (1800 3350) $PN DN80
J 0
(1810 3360);
DISPLAY 0.680851 (1810 3360);
PAINT MONO (1810 3360);
FORCEPROP 0 LASTPIN (1800 3400) $PN DA76
J 0
(1810 3410);
DISPLAY 0.680851 (1810 3410);
PAINT MONO (1810 3410);
FORCEPROP 0 LASTPIN (1800 3450) $PN CV77
J 0
(1810 3460);
DISPLAY 0.680851 (1810 3460);
PAINT MONO (1810 3460);
FORCEPROP 0 LASTPIN (1800 3500) $PN CR76
J 0
(1810 3510);
DISPLAY 0.680851 (1810 3510);
PAINT MONO (1810 3510);
FORCEPROP 0 LASTPIN (1800 3550) $PN CU74
J 0
(1810 3560);
DISPLAY 0.680851 (1810 3560);
PAINT MONO (1810 3560);
FORCEPROP 0 LASTPIN (1800 3600) $PN CM77
J 0
(1810 3610);
DISPLAY 0.680851 (1810 3610);
PAINT MONO (1810 3610);
FORCEPROP 0 LASTPIN (1800 3650) $PN CJ78
J 0
(1810 3660);
DISPLAY 0.680851 (1810 3660);
PAINT MONO (1810 3660);
FORCEPROP 0 LASTPIN (1800 3700) $PN CL76
J 0
(1810 3710);
DISPLAY 0.680851 (1810 3710);
PAINT MONO (1810 3710);
FORCEPROP 0 LASTPIN (1800 3750) $PN CF77
J 0
(1810 3760);
DISPLAY 0.680851 (1810 3760);
PAINT MONO (1810 3760);
FORCEPROP 0 LASTPIN (1800 3800) $PN CH75
J 0
(1810 3810);
DISPLAY 0.680851 (1810 3810);
PAINT MONO (1810 3810);
FORCEPROP 0 LASTPIN (1800 3850) $PN CK75
J 0
(1810 3860);
DISPLAY 0.680851 (1810 3860);
PAINT MONO (1810 3860);
FORCEPROP 0 LASTPIN (1800 3900) $PN CW74
J 0
(1810 3910);
DISPLAY 0.680851 (1810 3910);
PAINT MONO (1810 3910);
FORCEPROP 0 LASTPIN (1800 3950) $PN CD73
J 0
(1810 3960);
DISPLAY 0.680851 (1810 3960);
PAINT MONO (1810 3960);
FORCEPROP 2 LAST CDS_LIB pure_quanta
J 0
(600 2750);
DISPLAY INVISIBLE (600 2750);
FORCEPROP 1 LAST NEEDS_NO_SIZE TRUE
J 0
(600 2750);
DISPLAY 0.723404 (600 2750);
PAINT GREEN (600 2750);
DISPLAY INVISIBLE (600 2750);
FORCEPROP 1 LAST CDS_LMAN_SYM_OUTLINE -1050,1350,1050,-1350
J 0
(600 2750);
DISPLAY 0.468085 (600 2750);
PAINT GREEN (600 2750);
DISPLAY INVISIBLE (600 2750);
FORCEPROP 2 LAST CDS_LOCATION U1
J 0
(-450 4425);
DISPLAY 1.021277 (-450 4425);
DISPLAY INVISIBLE (-450 4425);
FORCEPROP 0 LAST $SEC 25
J 0
(-450 4425);
DISPLAY 0.680851 (-450 4425);
PAINT MONO (-450 4425);
DISPLAY INVISIBLE (-450 4425);
FORCEPROP 2 LAST CDS_SEC 25
J 0
(-450 4425);
DISPLAY 1.021277 (-450 4425);
DISPLAY INVISIBLE (-450 4425);
FORCEPROP 1 LAST PATH I16
J 0
(600 2750);
DISPLAY 0.723404 (600 2750);
PAINT GREEN (600 2750);
DISPLAY INVISIBLE (600 2750);
FORCEADD UNIVERSAL_GND..1
(-900 1225);
FORCEPROP 3 LASTPIN (-900 1275) SIG_NAME GND\g
J 0
(-890 1285);
DISPLAY 0.659574 (-890 1285);
PAINT MONO (-890 1285);
DISPLAY INVISIBLE (-890 1285);
FORCEPROP 2 LAST CDS_LIB logical_power
J 0
(-900 1225);
DISPLAY INVISIBLE (-900 1225);
FORCEPROP 1 LAST HDL_POWER GND
J 1
(-875 1150);
DISPLAY 0.872340 (-875 1150);
PAINT GREEN (-875 1150);
DISPLAY INVISIBLE (-875 1150);
FORCEPROP 1 LAST PATH I17
J 0
(-825 1225);
DISPLAY 0.872340 (-825 1225);
PAINT AQUA (-825 1225);
DISPLAY INVISIBLE (-825 1225);
FORCEADD QUANTA_TITLE_BLOCK_C..1
(5200 -1550);
FORCEPROP 0 LAST CDS_CON_LAST_MODIFIED Fri Aug 25 14:00:47 2023
J 0
(3315 -1535);
PAINT MONO (3315 -1535);
DISPLAY INVISIBLE (3315 -1535);
FORCEPROP 1 LAST CUSTOM_TXT_CDS <CON_LAST_MODIFIED>
J 0
(3315 -1535);
DISPLAY 0.978723 (3315 -1535);
FORCEPROP 2 LAST CUSTOM_TXT_CDS <XR_PAGE_TITLE>
J 0
(-2690 3700);
DISPLAY 0.638298 (-2690 3700);
PAINT PINK (-2690 3700);
DISPLAY INVISIBLE (-2690 3700);
FORCEPROP 2 LAST CUSTOM_TXT_CDS <Q_NUMBER>
J 0
(3797 -1447);
DISPLAY 1.212766 (3797 -1447);
FORCEPROP 1 LAST CUSTOM_TXT_CDS <NAME_2>
J 0
(2025 -1500);
FORCEPROP 1 LAST CUSTOM_TXT_CDS <NAME_1>
J 0
(2025 -1375);
FORCEPROP 1 LAST CUSTOM_TXT_CDS <Q_PROJ>
J 0
(2818 -1448);
DISPLAY 1.212766 (2818 -1448);
FORCEPROP 1 LAST CUSTOM_TXT_CDS <Q_REV>
J 0
(5016 -1447);
DISPLAY 1.212766 (5016 -1447);
FORCEPROP 1 LAST CUSTOM_TXT_CDS <CON_PAGE_NUM> OF <CON_TOTAL_PAGES>
J 0
(4754 -1532);
DISPLAY 0.978723 (4754 -1532);
FORCEPROP 1 LAST Q_TITLE SPR CPU1 - UPI3 (23 OF 30)
J 0
(-4166 -1524);
DISPLAY 1.957447 (-4166 -1524);
PAINT GREEN (-4166 -1524);
FORCEPROP 1 LAST Q_DEPT 
J 1
(1437 -1501);
DISPLAY 1.957447 (1437 -1501);
PAINT GREEN (1437 -1501);
FORCEPROP 1 LAST COMMENT_BODY TRUE
J 0
(5212 -1563);
DISPLAY 0.978723 (5212 -1563);
PAINT GREEN (5212 -1563);
DISPLAY INVISIBLE (5212 -1563);
FORCEPROP 2 LAST CDS_XR_PAGE_TITLE CR-66 : @S9S_MB_2U_LIB.S9S_MB_2U(SCH_1):PAGE66
J 0
(-2690 3700);
DISPLAY 0.638298 (-2690 3700);
PAINT PINK (-2690 3700);
DISPLAY INVISIBLE (-2690 3700);
FORCEPROP 2 LAST PAGE_BORDER TRUE
J 0
(-2690 3700);
DISPLAY 0.638298 (-2690 3700);
PAINT PINK (-2690 3700);
DISPLAY INVISIBLE (-2690 3700);
FORCEPROP 1 LAST CDS_LMAN_SYM_OUTLINE -9475,6775,100,-125
J 0
(5200 -1550);
DISPLAY 0.468085 (5200 -1550);
PAINT GREEN (5200 -1550);
DISPLAY INVISIBLE (5200 -1550);
FORCEPROP 2 LAST CDS_LIB pure_quanta
J 0
(5200 -1550);
PAINT MONO (5200 -1550);
DISPLAY INVISIBLE (5200 -1550);
WIRE 16 -1 (-900 1550)(-900 1275);
WIRE 16 -1 (-900 1600)(-900 1550);
WIRE 16 -1 (-900 1550)(-600 1550);
WIRE 16 -1 (-900 1600)(-600 1600);
WIRE 16 -1 (-900 1650)(-900 1600);
WIRE 16 -1 (-900 1650)(-600 1650);
WIRE 16 -1 (-900 1700)(-900 1650);
WIRE 16 -1 (-900 1700)(-600 1700);
WIRE 16 -1 (-900 1750)(-900 1700);
WIRE 16 -1 (-900 1750)(-600 1750);
WIRE 16 -1 (-900 1800)(-900 1750);
WIRE 16 -1 (-900 1800)(-600 1800);
WIRE 16 -1 (-900 1850)(-900 1800);
WIRE 16 -1 (-900 1850)(-600 1850);
WIRE 16 -1 (-900 1900)(-900 1850);
WIRE 16 -1 (-900 1900)(-600 1900);
WIRE 16 -1 (-900 1950)(-900 1900);
WIRE 16 -1 (-900 1950)(-600 1950);
WIRE 16 -1 (-900 2000)(-900 1950);
WIRE 16 -1 (-900 2000)(-600 2000);
WIRE 16 -1 (-900 2050)(-900 2000);
WIRE 16 -1 (-900 2050)(-600 2050);
WIRE 16 -1 (-900 2100)(-900 2050);
WIRE 16 -1 (-900 2100)(-600 2100);
WIRE 16 -1 (-900 2150)(-900 2100);
WIRE 16 -1 (-900 2150)(-600 2150);
WIRE 16 -1 (-900 2200)(-900 2150);
WIRE 16 -1 (-900 2200)(-600 2200);
WIRE 16 -1 (-900 2250)(-900 2200);
WIRE 16 -1 (-900 2250)(-600 2250);
WIRE 16 -1 (-900 2300)(-900 2250);
WIRE 16 -1 (-900 2300)(-600 2300);
WIRE 16 -1 (-900 2350)(-900 2300);
WIRE 16 -1 (-900 2350)(-600 2350);
WIRE 16 -1 (-900 2400)(-900 2350);
WIRE 16 -1 (-900 2400)(-600 2400);
WIRE 16 -1 (-900 2450)(-900 2400);
WIRE 16 -1 (-900 2450)(-600 2450);
WIRE 16 -1 (-900 2500)(-900 2450);
WIRE 16 -1 (-900 2500)(-600 2500);
WIRE 16 -1 (-900 2550)(-900 2500);
WIRE 16 -1 (-900 2550)(-600 2550);
WIRE 16 -1 (-900 2600)(-900 2550);
WIRE 16 -1 (-900 2600)(-600 2600);
WIRE 16 -1 (-900 2650)(-900 2600);
WIRE 16 -1 (-900 2650)(-600 2650);
WIRE 16 -1 (-900 2700)(-900 2650);
WIRE 16 -1 (-900 2700)(-600 2700);
WIRE 16 -1 (-900 2800)(-900 2700);
WIRE 16 -1 (-900 2800)(-600 2800);
WIRE 16 -1 (-900 2850)(-900 2800);
WIRE 16 -1 (-900 2850)(-600 2850);
WIRE 16 -1 (-900 2900)(-900 2850);
WIRE 16 -1 (-900 2900)(-600 2900);
WIRE 16 -1 (-900 2950)(-900 2900);
WIRE 16 -1 (-900 2950)(-600 2950);
WIRE 16 -1 (-900 3000)(-900 2950);
WIRE 16 -1 (-900 3000)(-600 3000);
WIRE 16 -1 (-900 3050)(-900 3000);
WIRE 16 -1 (-900 3050)(-600 3050);
WIRE 16 -1 (-900 3100)(-900 3050);
WIRE 16 -1 (-900 3100)(-600 3100);
WIRE 16 -1 (-900 3150)(-900 3100);
WIRE 16 -1 (-900 3150)(-600 3150);
WIRE 16 -1 (-900 3200)(-900 3150);
WIRE 16 -1 (-900 3200)(-600 3200);
WIRE 16 -1 (-900 3250)(-900 3200);
WIRE 16 -1 (-900 3250)(-600 3250);
WIRE 16 -1 (-900 3300)(-900 3250);
WIRE 16 -1 (-900 3300)(-600 3300);
WIRE 16 -1 (-900 3350)(-900 3300);
WIRE 16 -1 (-900 3350)(-600 3350);
WIRE 16 -1 (-900 3400)(-900 3350);
WIRE 16 -1 (-900 3400)(-600 3400);
WIRE 16 -1 (-900 3450)(-900 3400);
WIRE 16 -1 (-900 3450)(-600 3450);
WIRE 16 -1 (-900 3500)(-900 3450);
WIRE 16 -1 (-900 3500)(-600 3500);
WIRE 16 -1 (-900 3550)(-900 3500);
WIRE 16 -1 (-900 3550)(-600 3550);
WIRE 16 -1 (-900 3600)(-900 3550);
WIRE 16 -1 (-900 3600)(-600 3600);
WIRE 16 -1 (-900 3650)(-900 3600);
WIRE 16 -1 (-900 3650)(-600 3650);
WIRE 16 -1 (-900 3700)(-900 3650);
WIRE 16 -1 (-900 3700)(-600 3700);
WIRE 16 -1 (-900 3750)(-900 3700);
WIRE 16 -1 (-900 3750)(-600 3750);
WIRE 16 -1 (-900 3800)(-900 3750);
WIRE 16 -1 (-900 3800)(-600 3800);
WIRE 16 -1 (-900 3850)(-900 3800);
WIRE 16 -1 (-900 3850)(-600 3850);
WIRE 16 -1 (-900 3900)(-900 3850);
WIRE 16 -1 (-900 3900)(-600 3900);
WIRE 16 -1 (-900 3950)(-900 3900);
WIRE 16 -1 (-900 3950)(-600 3950);
WIRE 16 2175 (1250 1250)(2075 1250);
WIRE 16 2175 (2075 4225)(2075 1250);
WIRE 16 2175 (1250 4225)(1250 1250);
WIRE 16 2175 (1250 4225)(2075 4225);
DOT 1 (-900 2350);
DOT 1 (-900 3900);
DOT 1 (-900 3750);
DOT 1 (-900 3800);
DOT 1 (-900 3850);
DOT 1 (-900 3700);
DOT 1 (-900 3650);
DOT 1 (-900 3600);
DOT 1 (-900 3550);
DOT 1 (-900 3500);
DOT 1 (-900 3450);
DOT 1 (-900 3400);
DOT 1 (-900 3350);
DOT 1 (-900 3300);
DOT 1 (-900 3250);
DOT 1 (-900 3200);
DOT 1 (-900 3150);
DOT 1 (-900 3100);
DOT 1 (-900 3050);
DOT 1 (-900 3000);
DOT 1 (-900 2950);
DOT 1 (-900 2900);
DOT 1 (-900 2850);
DOT 1 (-900 2800);
DOT 1 (-900 2700);
DOT 1 (-900 2650);
DOT 1 (-900 2600);
DOT 1 (-900 2550);
DOT 1 (-900 2500);
DOT 1 (-900 2450);
DOT 1 (-900 2400);
DOT 1 (-900 2300);
DOT 1 (-900 2250);
DOT 1 (-900 2200);
DOT 1 (-900 2150);
DOT 1 (-900 2100);
DOT 1 (-900 2050);
DOT 1 (-900 2000);
DOT 1 (-900 1950);
DOT 1 (-900 1900);
DOT 1 (-900 1850);
DOT 1 (-900 1800);
DOT 1 (-900 1750);
DOT 1 (-900 1700);
DOT 1 (-900 1550);
DOT 1 (-900 1600);
DOT 1 (-900 1650);
FORCENOTE
20211129 CHANGE TX FLOATING
(300 1000) 0;
DISPLAY LEFT (300 1000);
DISPLAY 2.510638 (300 1000);
PAINT PINK (300 1000);
FORCENOTE
20211122 MODIFY FOR GT
(-3875 4775) 0;
DISPLAY LEFT (-3875 4775);
DISPLAY 2.510638 (-3875 4775);
PAINT PINK (-3875 4775);
QUIT
